FILE_TYPE = CONNECTIVITY;
{Allegro Design Entry HDL 17.2-2016 S066 (3851973) 4/6/2020}
"PAGE_NUMBER" = 21;
0"NC";
END.
